# T6G (Grand Teton) — schematic netlist excerpt (pin names and nets, part order shuffled) for the footprints in the layout excerpt that follows; sources: Cadence DE-HDL packaged netlist, KiCad conversion of 04192023_DAF0TMB3IC0_F0TG_MB_C_brd_V02_OCP.brd

PR4524  Q_RES  10M 1% CHIP  pkg 0402LF  page 134 : A = P12V_OCP_SFF ; B = P12V_OCP_GATE_1
C664  Q_CAP  0.1UF 10V 10% X7S  pkg C0201  page 289 : A = P1V8_CPU0_RT_1D ; B = GND
PC6020  Q_CAP  100NF 50V 10% X7R  pkg C0402  page 269 : A = P12V_AUX ; B = GND

(kicad_pcb
	(version 20260206)
	(generator "pcbnew")
	(generator_version "10.0")
	(general
		(thickness 1.6)
		(legacy_teardrops no)
	)
	(paper "A4")
	(title_block
		(title "04192023_DAF0TMB3IC0_F0TG_MB_C_brd_V02_OCP.brd")
		(comment 1 "Grand Teton / footprints 3890-3892 of 8354")
	)
	(layers
		(0 "F.Cu" signal "TOP")
		(4 "In1.Cu" signal "GND")
		(6 "In2.Cu" signal "IN1")
		(8 "In3.Cu" signal "GND1")
		(10 "In4.Cu" signal "IN2")
		(12 "In5.Cu" signal "GND2")
		(14 "In6.Cu" signal "IN3")
		(16 "In7.Cu" signal "GND3")
		(18 "In8.Cu" signal "VCC")
		(20 "In9.Cu" signal "VCC1")
		(22 "In10.Cu" signal "GND4")
		(24 "In11.Cu" signal "IN4")
		(26 "In12.Cu" signal "GND5")
		(28 "In13.Cu" signal "IN5")
		(30 "In14.Cu" signal "GND6")
		(32 "In15.Cu" signal "IN6")
		(34 "In16.Cu" signal "GND7")
		(2 "B.Cu" signal "BOTTOM")
		(9 "F.Adhes" user "F.Adhesive")
		(11 "B.Adhes" user "B.Adhesive")
		(13 "F.Paste" user "Package Geometry/Pastemask Top")
		(15 "B.Paste" user "Package Geometry/Pastemask Bottom")
		(5 "F.SilkS" user "Ref Des/Silkscreen Top")
		(7 "B.SilkS" user "Ref Des/Silkscreen Bottom")
		(1 "F.Mask" user "Board Geometry/Soldermask Top")
		(3 "B.Mask" user "Board Geometry/Soldermask Bottom")
		(17 "Dwgs.User" user "User.Drawings")
		(19 "Cmts.User" user "User.Comments")
		(21 "Eco1.User" user "User.Eco1")
		(23 "Eco2.User" user "User.Eco2")
		(25 "Edge.Cuts" user "Board Geometry/Outline")
		(27 "Margin" user)
		(31 "F.CrtYd" user "Package Geometry/Place Bound Top")
		(29 "B.CrtYd" user "Package Geometry/Place Bound Bottom")
		(35 "F.Fab" user "Ref Des/Assembly Top")
		(33 "B.Fab" user "Ref Des/Assembly Bottom")
	)
	(footprint ""
		(layer "F.Cu")
		(at 137.196068 -74.236072 180)
		(property "Reference" "PC6020"
			(at 0 0 180)
			(layer "F.SilkS")
			(hide yes)
			(effects
				(font
					(size 1.27 1.27)
				)
			)
		)
		(property "Value" ""
			(at 0 0 180)
			(layer "F.Fab")
			(effects
				(font
					(size 1.27 1.27)
				)
			)
		)
		(duplicate_pad_numbers_are_jumpers no)
		(fp_line
			(start 0.7874 0.4064)
			(end -0.7874 0.4064)
			(stroke
				(width 0.1524)
				(type default)
			)
			(layer "F.SilkS")
		)
		(fp_line
			(start 0.7874 -0.4064)
			(end 0.7874 0.4064)
			(stroke
				(width 0.1524)
				(type default)
			)
			(layer "F.SilkS")
		)
		(fp_line
			(start -0.7874 0.4064)
			(end -0.7874 -0.4064)
			(stroke
				(width 0.1524)
				(type default)
			)
			(layer "F.SilkS")
		)
		(fp_line
			(start -0.7874 -0.4064)
			(end 0.7874 -0.4064)
			(stroke
				(width 0.1524)
				(type default)
			)
			(layer "F.SilkS")
		)
		(fp_line
			(start 0.67945 0.3048)
			(end 0.120396 0.3048)
			(stroke
				(width 0.1)
				(type default)
			)
			(layer "F.Fab")
		)
		(fp_line
			(start 0.67945 -0.3048)
			(end 0.67945 0.3048)
			(stroke
				(width 0.1)
				(type default)
			)
			(layer "F.Fab")
		)
		(fp_line
			(start 0.12065 -0.2794)
			(end 0.12065 -0.3048)
			(stroke
				(width 0.1)
				(type default)
			)
			(layer "F.Fab")
		)
		(fp_line
			(start 0.12065 -0.3048)
			(end 0.67945 -0.3048)
			(stroke
				(width 0.1)
				(type default)
			)
			(layer "F.Fab")
		)
		(fp_line
			(start 0.120396 0.3048)
			(end 0.120396 0.2794)
			(stroke
				(width 0.1)
				(type default)
			)
			(layer "F.Fab")
		)
		(fp_line
			(start 0.120396 0.2794)
			(end -0.12065 0.2794)
			(stroke
				(width 0.1)
				(type default)
			)
			(layer "F.Fab")
		)
		(fp_line
			(start -0.12065 0.3048)
			(end -0.67945 0.3048)
			(stroke
				(width 0.1)
				(type default)
			)
			(layer "F.Fab")
		)
		(fp_line
			(start -0.12065 0.2794)
			(end -0.12065 0.3048)
			(stroke
				(width 0.1)
				(type default)
			)
			(layer "F.Fab")
		)
		(fp_line
			(start -0.12065 -0.2794)
			(end 0.12065 -0.2794)
			(stroke
				(width 0.1)
				(type default)
			)
			(layer "F.Fab")
		)
		(fp_line
			(start -0.12065 -0.305054)
			(end -0.12065 -0.2794)
			(stroke
				(width 0.1)
				(type default)
			)
			(layer "F.Fab")
		)
		(fp_line
			(start -0.67945 0.3048)
			(end -0.67945 -0.305054)
			(stroke
				(width 0.1)
				(type default)
			)
			(layer "F.Fab")
		)
		(fp_line
			(start -0.67945 -0.305054)
			(end -0.12065 -0.305054)
			(stroke
				(width 0.1)
				(type default)
			)
			(layer "F.Fab")
		)
		(pad "1" smd circle
			(at -0.40005 0 180)
			(size 0 0)
			(layers "F.Cu" "F.Mask" "F.Paste")
			(net "P12V_AUX")
		)
		(pad "2" smd circle
			(at 0.40005 0 180)
			(size 0 0)
			(layers "F.Cu" "F.Mask" "F.Paste")
			(net "GND")
		)
	)
	(footprint ""
		(layer "F.Cu")
		(at 295.30421 -404.422102 -90)
		(property "Reference" "C664"
			(at 0 0 270)
			(layer "F.SilkS")
			(hide yes)
			(effects
				(font
					(size 1.27 1.27)
				)
			)
		)
		(property "Value" ""
			(at 0 0 270)
			(layer "F.Fab")
			(effects
				(font
					(size 1.27 1.27)
				)
			)
		)
		(duplicate_pad_numbers_are_jumpers no)
		(fp_line
			(start -0.299974 0.150114)
			(end -0.299974 -0.150114)
			(stroke
				(width 0.1)
				(type default)
			)
			(layer "F.Fab")
		)
		(fp_line
			(start 0.299974 0.150114)
			(end -0.299974 0.150114)
			(stroke
				(width 0.1)
				(type default)
			)
			(layer "F.Fab")
		)
		(fp_line
			(start -0.299974 -0.150114)
			(end 0.299974 -0.150114)
			(stroke
				(width 0.1)
				(type default)
			)
			(layer "F.Fab")
		)
		(fp_line
			(start 0.299974 -0.150114)
			(end 0.299974 0.150114)
			(stroke
				(width 0.1)
				(type default)
			)
			(layer "F.Fab")
		)
		(pad "1" smd rect
			(at -0.2667 0 270)
			(size 0.3048 0.381)
			(layers "F.Cu" "F.Mask" "F.Paste")
			(net "P1V8_CPU0_RT_1D")
		)
		(pad "2" smd rect
			(at 0.2667 0 270)
			(size 0.3048 0.381)
			(layers "F.Cu" "F.Mask" "F.Paste")
			(net "GND")
		)
	)
	(footprint ""
		(layer "F.Cu")
		(at 453.043544 -25.638506 180)
		(property "Reference" "PR4524"
			(at 0 0 180)
			(layer "F.SilkS")
			(hide yes)
			(effects
				(font
					(size 1.27 1.27)
				)
			)
		)
		(property "Value" ""
			(at 0 0 180)
			(layer "F.Fab")
			(effects
				(font
					(size 1.27 1.27)
				)
			)
		)
		(duplicate_pad_numbers_are_jumpers no)
		(fp_line
			(start 0.7874 0.4064)
			(end -0.7874 0.4064)
			(stroke
				(width 0.1524)
				(type default)
			)
			(layer "F.SilkS")
		)
		(fp_line
			(start 0.7874 -0.4064)
			(end 0.7874 0.4064)
			(stroke
				(width 0.1524)
				(type default)
			)
			(layer "F.SilkS")
		)
		(fp_line
			(start -0.7874 0.4064)
			(end -0.7874 -0.4064)
			(stroke
				(width 0.1524)
				(type default)
			)
			(layer "F.SilkS")
		)
		(fp_line
			(start -0.7874 -0.4064)
			(end 0.7874 -0.4064)
			(stroke
				(width 0.1524)
				(type default)
			)
			(layer "F.SilkS")
		)
		(fp_line
			(start 0.67945 0.3048)
			(end 0.120396 0.3048)
			(stroke
				(width 0.1)
				(type default)
			)
			(layer "F.Fab")
		)
		(fp_line
			(start 0.67945 -0.3048)
			(end 0.67945 0.3048)
			(stroke
				(width 0.1)
				(type default)
			)
			(layer "F.Fab")
		)
		(fp_line
			(start 0.12065 -0.2794)
			(end 0.12065 -0.3048)
			(stroke
				(width 0.1)
				(type default)
			)
			(layer "F.Fab")
		)
		(fp_line
			(start 0.12065 -0.3048)
			(end 0.67945 -0.3048)
			(stroke
				(width 0.1)
				(type default)
			)
			(layer "F.Fab")
		)
		(fp_line
			(start 0.120396 0.3048)
			(end 0.120396 0.2794)
			(stroke
				(width 0.1)
				(type default)
			)
			(layer "F.Fab")
		)
		(fp_line
			(start 0.120396 0.2794)
			(end -0.12065 0.2794)
			(stroke
				(width 0.1)
				(type default)
			)
			(layer "F.Fab")
		)
		(fp_line
			(start -0.12065 0.3048)
			(end -0.67945 0.3048)
			(stroke
				(width 0.1)
				(type default)
			)
			(layer "F.Fab")
		)
		(fp_line
			(start -0.12065 0.2794)
			(end -0.12065 0.3048)
			(stroke
				(width 0.1)
				(type default)
			)
			(layer "F.Fab")
		)
		(fp_line
			(start -0.12065 -0.2794)
			(end 0.12065 -0.2794)
			(stroke
				(width 0.1)
				(type default)
			)
			(layer "F.Fab")
		)
		(fp_line
			(start -0.12065 -0.305054)
			(end -0.12065 -0.2794)
			(stroke
				(width 0.1)
				(type default)
			)
			(layer "F.Fab")
		)
		(fp_line
			(start -0.67945 0.3048)
			(end -0.67945 -0.305054)
			(stroke
				(width 0.1)
				(type default)
			)
			(layer "F.Fab")
		)
		(fp_line
			(start -0.67945 -0.305054)
			(end -0.12065 -0.305054)
			(stroke
				(width 0.1)
				(type default)
			)
			(layer "F.Fab")
		)
		(pad "1" smd circle
			(at -0.40005 0 180)
			(size 0 0)
			(layers "F.Cu" "F.Mask" "F.Paste")
			(net "P12V_OCP_SFF")
		)
		(pad "2" smd circle
			(at 0.40005 0 180)
			(size 0 0)
			(layers "F.Cu" "F.Mask" "F.Paste")
			(net "P12V_OCP_GATE_1")
		)
	)
)
